# BASEBOARD_FAB2 (Tioga Pass) — schematic netlist excerpt (pin names and nets, part order shuffled) for the footprints in the layout excerpt that follows; sources: Cadence DE-HDL packaged netlist, KiCad conversion of Wiwynn_Tioga_Pass_MB.brd

C7P16  CAP_A  22.0UF 4V 20% X6S  pkg 0603V  page 76 : A = PVCCIO_CPU1 ; B = GND

U6W5  TTL1G126_A  74HC1G126 IC  pkg SOT  page 176
  OE  = DEBUG_CARD2_PRSNT
  A  = SPA_MID_DBG_TX
  Y  = SPA_MID_DBG2_TX_R

C5G95  CAP_A  22.0UF 4V 20% X6S  pkg 0603V  page 243 : A = PVDDQ_GHJ ; B = GND

(kicad_pcb
	(version 20260206)
	(generator "pcbnew")
	(generator_version "10.0")
	(general
		(thickness 1.6)
		(legacy_teardrops no)
	)
	(paper "A4")
	(title_block
		(title "Wiwynn_Tioga_Pass_MB.brd")
		(comment 1 "Tioga Pass / footprints 2798-2800 of 4770")
	)
	(layers
		(0 "F.Cu" signal "TOP")
		(4 "In1.Cu" signal "L2GND")
		(6 "In2.Cu" signal "L3")
		(8 "In3.Cu" signal "L4GND")
		(10 "In4.Cu" signal "L5")
		(12 "In5.Cu" signal "L6GND")
		(14 "In6.Cu" signal "L7VCC")
		(16 "In7.Cu" signal "L8VCC")
		(18 "In8.Cu" signal "L9GND")
		(20 "In9.Cu" signal "L10")
		(22 "In10.Cu" signal "L11GND")
		(24 "In11.Cu" signal "L12")
		(26 "In12.Cu" signal "L13GND")
		(2 "B.Cu" signal "BOTTOM")
		(9 "F.Adhes" user "F.Adhesive")
		(11 "B.Adhes" user "B.Adhesive")
		(13 "F.Paste" user "Package Geometry/Pastemask Top")
		(15 "B.Paste" user "Package Geometry/Pastemask Bottom")
		(5 "F.SilkS" user "Ref Des/Silkscreen Top")
		(7 "B.SilkS" user "Ref Des/Silkscreen Bottom")
		(1 "F.Mask" user "Board Geometry/Soldermask Top")
		(3 "B.Mask" user "Board Geometry/Soldermask Bottom")
		(17 "Dwgs.User" user "User.Drawings")
		(19 "Cmts.User" user "User.Comments")
		(21 "Eco1.User" user "User.Eco1")
		(23 "Eco2.User" user "User.Eco2")
		(25 "Edge.Cuts" user "Board Geometry/Outline")
		(27 "Margin" user)
		(31 "F.CrtYd" user "Package Geometry/Place Bound Top")
		(29 "B.CrtYd" user "Package Geometry/Place Bound Bottom")
		(35 "F.Fab" user "Ref Des/Assembly Top")
		(33 "B.Fab" user "Ref Des/Assembly Bottom")
	)
	(footprint ""
		(layer "B.Cu")
		(at 500.38 -143.002 -90)
		(property "Reference" "U6W5"
			(at 0.14986 2.621788 270)
			(unlocked yes)
			(layer "B.SilkS")
			(effects
				(font
					(size 1.27 0.964946)
					(thickness 0.000001)
				)
				(justify left mirror)
			)
		)
		(property "Value" ""
			(at 0 0 90)
			(layer "B.Fab")
			(effects
				(font
					(size 1.27 1.27)
				)
				(justify mirror)
			)
		)
		(duplicate_pad_numbers_are_jumpers no)
		(fp_circle
			(center 0.4699 -0.8382)
			(end 0.4699 -0.9652)
			(stroke
				(width 0.254)
				(type default)
			)
			(fill no)
			(layer "B.SilkS")
		)
		(fp_poly
			(pts
				(xy -0.21463 -0.450088) (xy -1.56337 -0.450088) (xy -1.56337 1.75006) (xy -0.21463 1.75006)
			)
			(stroke
				(width 0)
				(type default)
			)
			(fill no)
			(layer "B.CrtYd")
		)
		(fp_line
			(start -1.56337 1.75006)
			(end -0.21463 1.75006)
			(stroke
				(width 0.1)
				(type default)
			)
			(layer "B.Fab")
		)
		(fp_line
			(start -0.21463 1.75006)
			(end -0.21463 -0.450088)
			(stroke
				(width 0.1)
				(type default)
			)
			(layer "B.Fab")
		)
		(fp_line
			(start -1.56337 -0.450088)
			(end -1.56337 1.75006)
			(stroke
				(width 0.1)
				(type default)
			)
			(layer "B.Fab")
		)
		(fp_line
			(start -0.21463 -0.450088)
			(end -1.56337 -0.450088)
			(stroke
				(width 0.1)
				(type default)
			)
			(layer "B.Fab")
		)
		(fp_circle
			(center 0.4699 -0.8382)
			(end 0.4699 -0.9652)
			(stroke
				(width 0.254)
				(type default)
			)
			(fill no)
			(layer "B.Fab")
		)
		(pad "1" smd rect
			(at 0 0 90)
			(size 1.016 0.381)
			(layers "B.Cu" "B.Mask" "B.Paste")
			(net "DEBUG_CARD2_PRSNT")
		)
		(pad "2" smd rect
			(at 0 0.649986 90)
			(size 1.016 0.381)
			(layers "B.Cu" "B.Mask" "B.Paste")
			(net "SPA_MID_DBG_TX")
		)
		(pad "3" smd rect
			(at 0 1.299972 90)
			(size 1.016 0.381)
			(layers "B.Cu" "B.Mask" "B.Paste")
			(net "GND")
		)
		(pad "4" smd rect
			(at -1.778 1.299972 90)
			(size 1.016 0.381)
			(layers "B.Cu" "B.Mask" "B.Paste")
			(net "SPA_MID_DBG2_TX_R")
		)
		(pad "5" smd rect
			(at -1.778 0 90)
			(size 1.016 0.381)
			(layers "B.Cu" "B.Mask" "B.Paste")
			(net "P3V3_STBY")
		)
	)
	(footprint ""
		(layer "B.Cu")
		(at 115.353592 -71.841614 180)
		(property "Reference" "C7P16"
			(at 0 0 0)
			(layer "B.SilkS")
			(hide yes)
			(effects
				(font
					(size 1.27 1.27)
				)
				(justify mirror)
			)
		)
		(property "Value" ""
			(at 0 0 0)
			(layer "B.Fab")
			(effects
				(font
					(size 1.27 1.27)
				)
				(justify mirror)
			)
		)
		(duplicate_pad_numbers_are_jumpers no)
		(fp_poly
			(pts
				(xy 0.4953 -0.2032) (xy -0.4953 -0.2032) (xy -0.4953 1.6002) (xy 0.4953 1.6002)
			)
			(stroke
				(width 0)
				(type default)
			)
			(fill no)
			(layer "B.CrtYd")
		)
		(fp_line
			(start 0.4953 1.6002)
			(end 0.4953 -0.2032)
			(stroke
				(width 0.1)
				(type default)
			)
			(layer "B.Fab")
		)
		(fp_line
			(start 0.4953 -0.2032)
			(end -0.4953 -0.2032)
			(stroke
				(width 0.1)
				(type default)
			)
			(layer "B.Fab")
		)
		(fp_line
			(start -0.4953 1.6002)
			(end 0.4953 1.6002)
			(stroke
				(width 0.1)
				(type default)
			)
			(layer "B.Fab")
		)
		(fp_line
			(start -0.4953 -0.2032)
			(end -0.4953 1.6002)
			(stroke
				(width 0.1)
				(type default)
			)
			(layer "B.Fab")
		)
		(pad "1" smd rect
			(at 0 0)
			(size 0.762 0.889)
			(layers "B.Cu" "B.Mask" "B.Paste")
			(net "PVCCIO_CPU1")
		)
		(pad "2" smd rect
			(at 0 1.397)
			(size 0.762 0.889)
			(layers "B.Cu" "B.Mask" "B.Paste")
			(net "GND")
		)
		(zone
			(layer "B.Cu")
			(hatch none 0.5)
			(connect_pads
				(clearance 0)
			)
			(min_thickness 0.25)
			(keepout
				(tracks not_allowed)
				(vias allowed)
				(pads allowed)
				(copperpour not_allowed)
				(footprints allowed)
			)
			(placement
				(enabled no)
				(sheetname "")
			)
			(fill
				(thermal_gap 0.5)
				(thermal_bridge_width 0.5)
				(island_removal_mode 0)
			)
			(polygon
				(pts
					(xy 114.972592 -72.286114) (xy 115.734592 -72.286114) (xy 115.734592 -72.794114) (xy 114.972592 -72.794114)
				)
			)
		)
	)
	(footprint ""
		(layer "B.Cu")
		(at 107.8611 -12.954 90)
		(property "Reference" "C5G95"
			(at -1.14681 0.76708 180)
			(unlocked yes)
			(layer "B.SilkS")
			(effects
				(font
					(size 0.7874 0.5842)
					(thickness 0.1524)
				)
				(justify mirror)
			)
		)
		(property "Value" ""
			(at 0 0 90)
			(layer "B.Fab")
			(effects
				(font
					(size 1.27 1.27)
				)
				(justify mirror)
			)
		)
		(duplicate_pad_numbers_are_jumpers no)
		(fp_rect
			(start -0.4953 -0.2032)
			(end 0.4953 1.6002)
			(stroke
				(width 0)
				(type default)
			)
			(fill no)
			(layer "B.CrtYd")
		)
		(fp_line
			(start 0.4953 -0.2032)
			(end -0.4953 -0.2032)
			(stroke
				(width 0.1)
				(type default)
			)
			(layer "B.Fab")
		)
		(fp_line
			(start -0.4953 -0.2032)
			(end -0.4953 1.6002)
			(stroke
				(width 0.1)
				(type default)
			)
			(layer "B.Fab")
		)
		(fp_line
			(start 0.4953 1.6002)
			(end 0.4953 -0.2032)
			(stroke
				(width 0.1)
				(type default)
			)
			(layer "B.Fab")
		)
		(fp_line
			(start -0.4953 1.6002)
			(end 0.4953 1.6002)
			(stroke
				(width 0.1)
				(type default)
			)
			(layer "B.Fab")
		)
		(pad "1" smd rect
			(at 0 0 270)
			(size 0.762 0.889)
			(layers "B.Cu" "B.Mask" "B.Paste")
			(net "PVDDQ_GHJ")
		)
		(pad "2" smd rect
			(at 0 1.397 270)
			(size 0.762 0.889)
			(layers "B.Cu" "B.Mask" "B.Paste")
			(net "GND")
		)
		(zone
			(layer "B.Cu")
			(hatch none 0.5)
			(connect_pads
				(clearance 0)
			)
			(min_thickness 0.25)
			(keepout
				(tracks not_allowed)
				(vias allowed)
				(pads allowed)
				(copperpour not_allowed)
				(footprints allowed)
			)
			(placement
				(enabled no)
				(sheetname "")
			)
			(fill
				(thermal_gap 0.5)
				(thermal_bridge_width 0.5)
				(island_removal_mode 0)
			)
			(polygon
				(pts
					(xy 108.3056 -12.573) (xy 108.8136 -12.573) (xy 108.8136 -13.335) (xy 108.3056 -13.335)
				)
			)
		)
	)
)
